(kicad_pcb
	(version 20260206)
	(generator "pcbnew")
	(generator_version "10.0")
	(general
		(thickness 1.6)
		(legacy_teardrops no)
	)
	(paper "A4")
	(title_block
		(title "Wiwynn_Tioga_Pass_MB.brd")
		(comment 1 "Tioga Pass / footprints 1104-1110 of 4770")
	)
	(layers
		(0 "F.Cu" signal "TOP")
		(4 "In1.Cu" signal "L2GND")
		(6 "In2.Cu" signal "L3")
		(8 "In3.Cu" signal "L4GND")
		(10 "In4.Cu" signal "L5")
		(12 "In5.Cu" signal "L6GND")
		(14 "In6.Cu" signal "L7VCC")
		(16 "In7.Cu" signal "L8VCC")
		(18 "In8.Cu" signal "L9GND")
		(20 "In9.Cu" signal "L10")
		(22 "In10.Cu" signal "L11GND")
		(24 "In11.Cu" signal "L12")
		(26 "In12.Cu" signal "L13GND")
		(2 "B.Cu" signal "BOTTOM")
		(9 "F.Adhes" user "F.Adhesive")
		(11 "B.Adhes" user "B.Adhesive")
		(13 "F.Paste" user "Package Geometry/Pastemask Top")
		(15 "B.Paste" user "Package Geometry/Pastemask Bottom")
		(5 "F.SilkS" user "Ref Des/Silkscreen Top")
		(7 "B.SilkS" user "Ref Des/Silkscreen Bottom")
		(1 "F.Mask" user "Board Geometry/Soldermask Top")
		(3 "B.Mask" user "Board Geometry/Soldermask Bottom")
		(17 "Dwgs.User" user "User.Drawings")
		(19 "Cmts.User" user "User.Comments")
		(21 "Eco1.User" user "User.Eco1")
		(23 "Eco2.User" user "User.Eco2")
		(25 "Edge.Cuts" user "Board Geometry/Outline")
		(27 "Margin" user)
		(31 "F.CrtYd" user "Package Geometry/Place Bound Top")
		(29 "B.CrtYd" user "Package Geometry/Place Bound Bottom")
		(35 "F.Fab" user "Ref Des/Assembly Top")
		(33 "B.Fab" user "Ref Des/Assembly Bottom")
	)
	(footprint ""
		(layer "F.Cu")
		(at 197.108826 -69.324474 -90)
		(property "Reference" "C4D16"
			(at 0 0 270)
			(layer "F.SilkS")
			(hide yes)
			(effects
				(font
					(size 1.27 1.27)
				)
			)
		)
		(property "Value" ""
			(at 0 0 270)
			(layer "F.Fab")
			(effects
				(font
					(size 1.27 1.27)
				)
			)
		)
		(duplicate_pad_numbers_are_jumpers no)
		(fp_poly
			(pts
				(xy 0.3048 -0.1016) (xy 0.3048 0.9906) (xy -0.3048 0.9906) (xy -0.3048 -0.1016)
			)
			(stroke
				(width 0)
				(type default)
			)
			(fill no)
			(layer "F.CrtYd")
		)
		(fp_line
			(start -0.3048 0.9906)
			(end 0.3048 0.9906)
			(stroke
				(width 0.1)
				(type default)
			)
			(layer "F.Fab")
		)
		(fp_line
			(start 0.3048 0.9906)
			(end 0.3048 -0.1016)
			(stroke
				(width 0.1)
				(type default)
			)
			(layer "F.Fab")
		)
		(fp_line
			(start -0.3048 -0.1016)
			(end -0.3048 0.9906)
			(stroke
				(width 0.1)
				(type default)
			)
			(layer "F.Fab")
		)
		(fp_line
			(start 0.3048 -0.1016)
			(end -0.3048 -0.1016)
			(stroke
				(width 0.1)
				(type default)
			)
			(layer "F.Fab")
		)
		(pad "1" smd rect
			(at 0 0 270)
			(size 0.508 0.508)
			(layers "F.Cu" "F.Mask" "F.Paste")
			(net "VR_PVCCIN_CPU0_PH3_VCIN")
		)
		(pad "2" smd rect
			(at 0 0.889 270)
			(size 0.508 0.508)
			(layers "F.Cu" "F.Mask" "F.Paste")
			(net "GND")
		)
		(zone
			(layer "F.Cu")
			(hatch none 0.5)
			(connect_pads
				(clearance 0)
			)
			(min_thickness 0.25)
			(keepout
				(tracks not_allowed)
				(vias allowed)
				(pads allowed)
				(copperpour not_allowed)
				(footprints allowed)
			)
			(placement
				(enabled no)
				(sheetname "")
			)
			(fill
				(thermal_gap 0.5)
				(thermal_bridge_width 0.5)
				(island_removal_mode 0)
			)
			(polygon
				(pts
					(xy 196.473826 -69.578474) (xy 196.473826 -69.070474) (xy 196.854826 -69.070474) (xy 196.854826 -69.578474)
				)
			)
		)
		(zone
			(layer "F.Cu")
			(hatch none 0.5)
			(connect_pads
				(clearance 0)
			)
			(min_thickness 0.25)
			(keepout
				(tracks allowed)
				(vias not_allowed)
				(pads allowed)
				(copperpour not_allowed)
				(footprints allowed)
			)
			(placement
				(enabled no)
				(sheetname "")
			)
			(fill
				(thermal_gap 0.5)
				(thermal_bridge_width 0.5)
				(island_removal_mode 0)
			)
			(polygon
				(pts
					(xy 196.854826 -69.578474) (xy 196.854826 -69.070474) (xy 196.473826 -69.070474) (xy 196.473826 -69.578474)
				)
			)
		)
	)
	(footprint ""
		(layer "F.Cu")
		(at 364.75924 -137.52957 -90)
		(property "Reference" "R7A17"
			(at 0 0 270)
			(layer "F.SilkS")
			(hide yes)
			(effects
				(font
					(size 1.27 1.27)
				)
			)
		)
		(property "Value" ""
			(at 0 0 270)
			(layer "F.Fab")
			(effects
				(font
					(size 1.27 1.27)
				)
			)
		)
		(duplicate_pad_numbers_are_jumpers no)
		(fp_rect
			(start 0.2794 0.9906)
			(end -0.2794 -0.1016)
			(stroke
				(width 0)
				(type default)
			)
			(fill no)
			(layer "F.CrtYd")
		)
		(fp_line
			(start -0.2794 0.9906)
			(end 0.2794 0.9906)
			(stroke
				(width 0.1)
				(type default)
			)
			(layer "F.Fab")
		)
		(fp_line
			(start 0.2794 0.9906)
			(end 0.2794 -0.1016)
			(stroke
				(width 0.1)
				(type default)
			)
			(layer "F.Fab")
		)
		(fp_line
			(start -0.2794 -0.1016)
			(end -0.2794 0.9906)
			(stroke
				(width 0.1)
				(type default)
			)
			(layer "F.Fab")
		)
		(fp_line
			(start 0.2794 -0.1016)
			(end -0.2794 -0.1016)
			(stroke
				(width 0.1)
				(type default)
			)
			(layer "F.Fab")
		)
		(pad "1" smd rect
			(at 0 0 270)
			(size 0.508 0.508)
			(layers "F.Cu" "F.Mask" "F.Paste")
			(net "SVID_CLK1_CPU0_R")
		)
		(pad "2" smd rect
			(at 0 0.889 270)
			(size 0.508 0.508)
			(layers "F.Cu" "F.Mask" "F.Paste")
			(net "SVID_CLK_PVDDQ_DEF")
		)
		(zone
			(layer "F.Cu")
			(hatch none 0.5)
			(connect_pads
				(clearance 0)
			)
			(min_thickness 0.25)
			(keepout
				(tracks allowed)
				(vias not_allowed)
				(pads allowed)
				(copperpour not_allowed)
				(footprints allowed)
			)
			(placement
				(enabled no)
				(sheetname "")
			)
			(fill
				(thermal_gap 0.5)
				(thermal_bridge_width 0.5)
				(island_removal_mode 0)
			)
			(polygon
				(pts
					(xy 364.12424 -137.27557) (xy 364.50524 -137.27557) (xy 364.50524 -137.78357) (xy 364.12424 -137.78357)
				)
			)
		)
		(zone
			(layer "F.Cu")
			(hatch none 0.5)
			(connect_pads
				(clearance 0)
			)
			(min_thickness 0.25)
			(keepout
				(tracks not_allowed)
				(vias allowed)
				(pads allowed)
				(copperpour not_allowed)
				(footprints allowed)
			)
			(placement
				(enabled no)
				(sheetname "")
			)
			(fill
				(thermal_gap 0.5)
				(thermal_bridge_width 0.5)
				(island_removal_mode 0)
			)
			(polygon
				(pts
					(xy 364.12424 -137.27557) (xy 364.50524 -137.27557) (xy 364.50524 -137.78357) (xy 364.12424 -137.78357)
				)
			)
		)
	)
	(footprint ""
		(layer "F.Cu")
		(at 79.551022 -125.88113 -90)
		(property "Reference" "C2B2"
			(at 0 0 270)
			(layer "F.SilkS")
			(hide yes)
			(effects
				(font
					(size 1.27 1.27)
				)
			)
		)
		(property "Value" ""
			(at 0 0 270)
			(layer "F.Fab")
			(effects
				(font
					(size 1.27 1.27)
				)
			)
		)
		(duplicate_pad_numbers_are_jumpers no)
		(fp_rect
			(start -0.500126 1.598422)
			(end 0.500126 -0.201422)
			(stroke
				(width 0)
				(type default)
			)
			(fill no)
			(layer "F.CrtYd")
		)
		(fp_line
			(start -0.500126 1.598422)
			(end -0.500126 -0.201422)
			(stroke
				(width 0.1)
				(type default)
			)
			(layer "F.Fab")
		)
		(fp_line
			(start 0.500126 1.598422)
			(end -0.500126 1.598422)
			(stroke
				(width 0.1)
				(type default)
			)
			(layer "F.Fab")
		)
		(fp_line
			(start -0.500126 -0.201422)
			(end 0.500126 -0.201422)
			(stroke
				(width 0.1)
				(type default)
			)
			(layer "F.Fab")
		)
		(fp_line
			(start 0.500126 -0.201422)
			(end 0.500126 1.598422)
			(stroke
				(width 0.1)
				(type default)
			)
			(layer "F.Fab")
		)
		(pad "1" smd rect
			(at 0 0 180)
			(size 0.889 0.9906)
			(layers "F.Cu" "F.Mask" "F.Paste")
			(net "PVDDQ_KLM")
		)
		(pad "2" smd rect
			(at 0 1.397 180)
			(size 0.889 0.9906)
			(layers "F.Cu" "F.Mask" "F.Paste")
			(net "GND")
		)
		(zone
			(layer "F.Cu")
			(hatch none 0.5)
			(connect_pads
				(clearance 0)
			)
			(min_thickness 0.25)
			(keepout
				(tracks not_allowed)
				(vias allowed)
				(pads allowed)
				(copperpour not_allowed)
				(footprints allowed)
			)
			(placement
				(enabled no)
				(sheetname "")
			)
			(fill
				(thermal_gap 0.5)
				(thermal_bridge_width 0.5)
				(island_removal_mode 0)
			)
			(polygon
				(pts
					(xy 78.598522 -126.37643) (xy 78.598522 -125.38583) (xy 79.106522 -125.38583) (xy 79.106522 -126.37643)
				)
			)
		)
		(zone
			(layer "F.Cu")
			(hatch none 0.5)
			(connect_pads
				(clearance 0)
			)
			(min_thickness 0.25)
			(keepout
				(tracks allowed)
				(vias not_allowed)
				(pads allowed)
				(copperpour not_allowed)
				(footprints allowed)
			)
			(placement
				(enabled no)
				(sheetname "")
			)
			(fill
				(thermal_gap 0.5)
				(thermal_bridge_width 0.5)
				(island_removal_mode 0)
			)
			(polygon
				(pts
					(xy 78.598522 -126.37643) (xy 78.598522 -125.38583) (xy 79.106522 -125.38583) (xy 79.106522 -126.37643)
				)
			)
		)
	)
	(footprint ""
		(layer "F.Cu")
		(at 183.007 -64.135 180)
		(property "Reference" "R4E6"
			(at 0 0 180)
			(layer "F.SilkS")
			(hide yes)
			(effects
				(font
					(size 1.27 1.27)
				)
			)
		)
		(property "Value" ""
			(at 0 0 180)
			(layer "F.Fab")
			(effects
				(font
					(size 1.27 1.27)
				)
			)
		)
		(duplicate_pad_numbers_are_jumpers no)
		(fp_rect
			(start 0.2794 -0.1016)
			(end -0.2794 0.9906)
			(stroke
				(width 0)
				(type default)
			)
			(fill no)
			(layer "F.CrtYd")
		)
		(fp_line
			(start 0.2794 0.9906)
			(end 0.2794 -0.1016)
			(stroke
				(width 0.1)
				(type default)
			)
			(layer "F.Fab")
		)
		(fp_line
			(start 0.2794 -0.1016)
			(end -0.2794 -0.1016)
			(stroke
				(width 0.1)
				(type default)
			)
			(layer "F.Fab")
		)
		(fp_line
			(start -0.2794 0.9906)
			(end 0.2794 0.9906)
			(stroke
				(width 0.1)
				(type default)
			)
			(layer "F.Fab")
		)
		(fp_line
			(start -0.2794 -0.1016)
			(end -0.2794 0.9906)
			(stroke
				(width 0.1)
				(type default)
			)
			(layer "F.Fab")
		)
		(pad "1" smd rect
			(at 0 0 180)
			(size 0.508 0.508)
			(layers "F.Cu" "F.Mask" "F.Paste")
			(net "SVID_CLK0_CPU0_R")
		)
		(pad "2" smd rect
			(at 0 0.889 180)
			(size 0.508 0.508)
			(layers "F.Cu" "F.Mask" "F.Paste")
			(net "SVID_VCLK_PVCCIN_CPU0")
		)
		(zone
			(layer "F.Cu")
			(hatch none 0.5)
			(connect_pads
				(clearance 0)
			)
			(min_thickness 0.25)
			(keepout
				(tracks not_allowed)
				(vias allowed)
				(pads allowed)
				(copperpour not_allowed)
				(footprints allowed)
			)
			(placement
				(enabled no)
				(sheetname "")
			)
			(fill
				(thermal_gap 0.5)
				(thermal_bridge_width 0.5)
				(island_removal_mode 0)
			)
			(polygon
				(pts
					(xy 182.753 -64.389) (xy 183.261 -64.389) (xy 183.261 -64.77) (xy 182.753 -64.77)
				)
			)
		)
		(zone
			(layer "F.Cu")
			(hatch none 0.5)
			(connect_pads
				(clearance 0)
			)
			(min_thickness 0.25)
			(keepout
				(tracks allowed)
				(vias not_allowed)
				(pads allowed)
				(copperpour not_allowed)
				(footprints allowed)
			)
			(placement
				(enabled no)
				(sheetname "")
			)
			(fill
				(thermal_gap 0.5)
				(thermal_bridge_width 0.5)
				(island_removal_mode 0)
			)
			(polygon
				(pts
					(xy 182.753 -64.389) (xy 183.261 -64.389) (xy 183.261 -64.77) (xy 182.753 -64.77)
				)
			)
		)
	)
	(footprint ""
		(layer "F.Cu")
		(at 403.8854 -124.841 90)
		(property "Reference" "R8B9"
			(at 0 0 90)
			(layer "F.SilkS")
			(hide yes)
			(effects
				(font
					(size 1.27 1.27)
				)
			)
		)
		(property "Value" ""
			(at 0 0 90)
			(layer "F.Fab")
			(effects
				(font
					(size 1.27 1.27)
				)
			)
		)
		(duplicate_pad_numbers_are_jumpers no)
		(fp_poly
			(pts
				(xy -0.2794 -0.1016) (xy 0.2794 -0.1016) (xy 0.2794 0.9906) (xy -0.2794 0.9906)
			)
			(stroke
				(width 0)
				(type default)
			)
			(fill no)
			(layer "F.CrtYd")
		)
		(fp_line
			(start 0.2794 -0.1016)
			(end -0.2794 -0.1016)
			(stroke
				(width 0.1)
				(type default)
			)
			(layer "F.Fab")
		)
		(fp_line
			(start -0.2794 -0.1016)
			(end -0.2794 0.9906)
			(stroke
				(width 0.1)
				(type default)
			)
			(layer "F.Fab")
		)
		(fp_line
			(start 0.2794 0.9906)
			(end 0.2794 -0.1016)
			(stroke
				(width 0.1)
				(type default)
			)
			(layer "F.Fab")
		)
		(fp_line
			(start -0.2794 0.9906)
			(end 0.2794 0.9906)
			(stroke
				(width 0.1)
				(type default)
			)
			(layer "F.Fab")
		)
		(pad "1" smd rect
			(at 0 0 90)
			(size 0.508 0.508)
			(layers "F.Cu" "F.Mask" "F.Paste")
			(net "A_USB2_COMP")
		)
		(pad "2" smd rect
			(at 0 0.889 90)
			(size 0.508 0.508)
			(layers "F.Cu" "F.Mask" "F.Paste")
			(net "GND")
		)
		(zone
			(layer "F.Cu")
			(hatch none 0.5)
			(connect_pads
				(clearance 0)
			)
			(min_thickness 0.25)
			(keepout
				(tracks allowed)
				(vias not_allowed)
				(pads allowed)
				(copperpour not_allowed)
				(footprints allowed)
			)
			(placement
				(enabled no)
				(sheetname "")
			)
			(fill
				(thermal_gap 0.5)
				(thermal_bridge_width 0.5)
				(island_removal_mode 0)
			)
			(polygon
				(pts
					(xy 404.1394 -124.587) (xy 404.1394 -125.095) (xy 404.5204 -125.095) (xy 404.5204 -124.587)
				)
			)
		)
		(zone
			(layer "F.Cu")
			(hatch none 0.5)
			(connect_pads
				(clearance 0)
			)
			(min_thickness 0.25)
			(keepout
				(tracks not_allowed)
				(vias allowed)
				(pads allowed)
				(copperpour not_allowed)
				(footprints allowed)
			)
			(placement
				(enabled no)
				(sheetname "")
			)
			(fill
				(thermal_gap 0.5)
				(thermal_bridge_width 0.5)
				(island_removal_mode 0)
			)
			(polygon
				(pts
					(xy 404.5204 -124.587) (xy 404.5204 -125.095) (xy 404.1394 -125.095) (xy 404.1394 -124.587)
				)
			)
		)
	)
	(footprint ""
		(layer "F.Cu")
		(at 173.609 -2.794 90)
		(property "Reference" "C4G21"
			(at 0 0 90)
			(layer "F.SilkS")
			(hide yes)
			(effects
				(font
					(size 1.27 1.27)
				)
			)
		)
		(property "Value" ""
			(at 0 0 90)
			(layer "F.Fab")
			(effects
				(font
					(size 1.27 1.27)
				)
			)
		)
		(duplicate_pad_numbers_are_jumpers no)
		(fp_rect
			(start 0.3048 0.9906)
			(end -0.3048 -0.1016)
			(stroke
				(width 0)
				(type default)
			)
			(fill no)
			(layer "F.CrtYd")
		)
		(fp_line
			(start 0.3048 -0.1016)
			(end -0.3048 -0.1016)
			(stroke
				(width 0.1)
				(type default)
			)
			(layer "F.Fab")
		)
		(fp_line
			(start -0.3048 -0.1016)
			(end -0.3048 0.9906)
			(stroke
				(width 0.1)
				(type default)
			)
			(layer "F.Fab")
		)
		(fp_line
			(start 0.3048 0.9906)
			(end 0.3048 -0.1016)
			(stroke
				(width 0.1)
				(type default)
			)
			(layer "F.Fab")
		)
		(fp_line
			(start -0.3048 0.9906)
			(end 0.3048 0.9906)
			(stroke
				(width 0.1)
				(type default)
			)
			(layer "F.Fab")
		)
		(pad "1" smd rect
			(at 0 0 90)
			(size 0.508 0.508)
			(layers "F.Cu" "F.Mask" "F.Paste")
			(net "VR_PVTT_GHJ_VREF")
		)
		(pad "2" smd rect
			(at 0 0.889 90)
			(size 0.508 0.508)
			(layers "F.Cu" "F.Mask" "F.Paste")
			(net "GND")
		)
		(zone
			(layer "F.Cu")
			(hatch none 0.5)
			(connect_pads
				(clearance 0)
			)
			(min_thickness 0.25)
			(keepout
				(tracks not_allowed)
				(vias allowed)
				(pads allowed)
				(copperpour not_allowed)
				(footprints allowed)
			)
			(placement
				(enabled no)
				(sheetname "")
			)
			(fill
				(thermal_gap 0.5)
				(thermal_bridge_width 0.5)
				(island_removal_mode 0)
			)
			(polygon
				(pts
					(xy 174.244 -3.048) (xy 173.863 -3.048) (xy 173.863 -2.54) (xy 174.244 -2.54)
				)
			)
		)
		(zone
			(layer "F.Cu")
			(hatch none 0.5)
			(connect_pads
				(clearance 0)
			)
			(min_thickness 0.25)
			(keepout
				(tracks allowed)
				(vias not_allowed)
				(pads allowed)
				(copperpour not_allowed)
				(footprints allowed)
			)
			(placement
				(enabled no)
				(sheetname "")
			)
			(fill
				(thermal_gap 0.5)
				(thermal_bridge_width 0.5)
				(island_removal_mode 0)
			)
			(polygon
				(pts
					(xy 174.244 -3.048) (xy 173.863 -3.048) (xy 173.863 -2.54) (xy 174.244 -2.54)
				)
			)
		)
	)
	(footprint ""
		(layer "F.Cu")
		(at 28.7528 -102.997 90)
		(property "Reference" "R1C35"
			(at 0 0 90)
			(layer "F.SilkS")
			(hide yes)
			(effects
				(font
					(size 1.27 1.27)
				)
			)
		)
		(property "Value" ""
			(at 0 0 90)
			(layer "F.Fab")
			(effects
				(font
					(size 1.27 1.27)
				)
			)
		)
		(duplicate_pad_numbers_are_jumpers no)
		(fp_poly
			(pts
				(xy -0.2794 -0.1016) (xy 0.2794 -0.1016) (xy 0.2794 0.9906) (xy -0.2794 0.9906)
			)
			(stroke
				(width 0)
				(type default)
			)
			(fill no)
			(layer "F.CrtYd")
		)
		(fp_line
			(start 0.2794 -0.1016)
			(end -0.2794 -0.1016)
			(stroke
				(width 0.1)
				(type default)
			)
			(layer "F.Fab")
		)
		(fp_line
			(start -0.2794 -0.1016)
			(end -0.2794 0.9906)
			(stroke
				(width 0.1)
				(type default)
			)
			(layer "F.Fab")
		)
		(fp_line
			(start 0.2794 0.9906)
			(end 0.2794 -0.1016)
			(stroke
				(width 0.1)
				(type default)
			)
			(layer "F.Fab")
		)
		(fp_line
			(start -0.2794 0.9906)
			(end 0.2794 0.9906)
			(stroke
				(width 0.1)
				(type default)
			)
			(layer "F.Fab")
		)
		(pad "1" smd rect
			(at 0 0 90)
			(size 0.508 0.508)
			(layers "F.Cu" "F.Mask" "F.Paste")
			(net "P3V3_STBY")
		)
		(pad "2" smd rect
			(at 0 0.889 90)
			(size 0.508 0.508)
			(layers "F.Cu" "F.Mask" "F.Paste")
			(net "FM_CPU1_SM_WP")
		)
		(zone
			(layer "F.Cu")
			(hatch none 0.5)
			(connect_pads
				(clearance 0)
			)
			(min_thickness 0.25)
			(keepout
				(tracks allowed)
				(vias not_allowed)
				(pads allowed)
				(copperpour not_allowed)
				(footprints allowed)
			)
			(placement
				(enabled no)
				(sheetname "")
			)
			(fill
				(thermal_gap 0.5)
				(thermal_bridge_width 0.5)
				(island_removal_mode 0)
			)
			(polygon
				(pts
					(xy 29.0068 -102.743) (xy 29.0068 -103.251) (xy 29.3878 -103.251) (xy 29.3878 -102.743)
				)
			)
		)
		(zone
			(layer "F.Cu")
			(hatch none 0.5)
			(connect_pads
				(clearance 0)
			)
			(min_thickness 0.25)
			(keepout
				(tracks not_allowed)
				(vias allowed)
				(pads allowed)
				(copperpour not_allowed)
				(footprints allowed)
			)
			(placement
				(enabled no)
				(sheetname "")
			)
			(fill
				(thermal_gap 0.5)
				(thermal_bridge_width 0.5)
				(island_removal_mode 0)
			)
			(polygon
				(pts
					(xy 29.3878 -102.743) (xy 29.3878 -103.251) (xy 29.0068 -103.251) (xy 29.0068 -102.743)
				)
			)
		)
	)
)
